# T6G (Grand Teton) — schematic netlist excerpt (pin names and nets, part order shuffled) for the footprints in the layout excerpt that follows; sources: Cadence DE-HDL packaged netlist, KiCad conversion of 04192023_DAF0TMB3IC0_F0TG_MB_C_brd_V02_OCP.brd

U8002  APX80929SAG7  APX809-29SAG-7 IC  pkg SOT23_123XI  page 142
  GND  = GND
  RESET_L  = OCP_V3_2_P3V3_R1_PWRGD
  VCC  = P3V3_OCP_V3_2_R

PC519  Q_CAP  0.22UF 16V 10% X7R  pkg 0402  page 225 : A = SW_PVDD11_S3_P1_BOOT1_RC ; B = SW_PVDD11_S3_P1_PH1
R6211  Q_RES  2.2K 5% CHIP  pkg 0402LF  page 250 : A = P3V3_AUX ; B = SMB_USB_CPU0_HUB1_SCL

(kicad_pcb
	(version 20260206)
	(generator "pcbnew")
	(generator_version "10.0")
	(general
		(thickness 1.6)
		(legacy_teardrops no)
	)
	(paper "A4")
	(title_block
		(title "04192023_DAF0TMB3IC0_F0TG_MB_C_brd_V02_OCP.brd")
		(comment 1 "Grand Teton / footprints 769-771 of 8354")
	)
	(layers
		(0 "F.Cu" signal "TOP")
		(4 "In1.Cu" signal "GND")
		(6 "In2.Cu" signal "IN1")
		(8 "In3.Cu" signal "GND1")
		(10 "In4.Cu" signal "IN2")
		(12 "In5.Cu" signal "GND2")
		(14 "In6.Cu" signal "IN3")
		(16 "In7.Cu" signal "GND3")
		(18 "In8.Cu" signal "VCC")
		(20 "In9.Cu" signal "VCC1")
		(22 "In10.Cu" signal "GND4")
		(24 "In11.Cu" signal "IN4")
		(26 "In12.Cu" signal "GND5")
		(28 "In13.Cu" signal "IN5")
		(30 "In14.Cu" signal "GND6")
		(32 "In15.Cu" signal "IN6")
		(34 "In16.Cu" signal "GND7")
		(2 "B.Cu" signal "BOTTOM")
		(9 "F.Adhes" user "F.Adhesive")
		(11 "B.Adhes" user "B.Adhesive")
		(13 "F.Paste" user "Package Geometry/Pastemask Top")
		(15 "B.Paste" user "Package Geometry/Pastemask Bottom")
		(5 "F.SilkS" user "Ref Des/Silkscreen Top")
		(7 "B.SilkS" user "Ref Des/Silkscreen Bottom")
		(1 "F.Mask" user "Board Geometry/Soldermask Top")
		(3 "B.Mask" user "Board Geometry/Soldermask Bottom")
		(17 "Dwgs.User" user "User.Drawings")
		(19 "Cmts.User" user "User.Comments")
		(21 "Eco1.User" user "User.Eco1")
		(23 "Eco2.User" user "User.Eco2")
		(25 "Edge.Cuts" user "Board Geometry/Outline")
		(27 "Margin" user)
		(31 "F.CrtYd" user "Package Geometry/Place Bound Top")
		(29 "B.CrtYd" user "Package Geometry/Place Bound Bottom")
		(35 "F.Fab" user "Ref Des/Assembly Top")
		(33 "B.Fab" user "Ref Des/Assembly Bottom")
	)
	(footprint ""
		(layer "F.Cu")
		(at 184.705752 -355.898958 -90)
		(property "Reference" "PC519"
			(at 0 0 270)
			(layer "F.SilkS")
			(hide yes)
			(effects
				(font
					(size 1.27 1.27)
				)
			)
		)
		(property "Value" ""
			(at 0 0 270)
			(layer "F.Fab")
			(effects
				(font
					(size 1.27 1.27)
				)
			)
		)
		(duplicate_pad_numbers_are_jumpers no)
		(fp_line
			(start -0.7874 0.4064)
			(end -0.7874 -0.4064)
			(stroke
				(width 0.1524)
				(type default)
			)
			(layer "F.SilkS")
		)
		(fp_line
			(start 0.7874 0.4064)
			(end -0.7874 0.4064)
			(stroke
				(width 0.1524)
				(type default)
			)
			(layer "F.SilkS")
		)
		(fp_line
			(start -0.7874 -0.4064)
			(end 0.7874 -0.4064)
			(stroke
				(width 0.1524)
				(type default)
			)
			(layer "F.SilkS")
		)
		(fp_line
			(start 0.7874 -0.4064)
			(end 0.7874 0.4064)
			(stroke
				(width 0.1524)
				(type default)
			)
			(layer "F.SilkS")
		)
		(fp_line
			(start -0.67945 0.3048)
			(end -0.67945 -0.305054)
			(stroke
				(width 0.1)
				(type default)
			)
			(layer "F.Fab")
		)
		(fp_line
			(start -0.12065 0.3048)
			(end -0.67945 0.3048)
			(stroke
				(width 0.1)
				(type default)
			)
			(layer "F.Fab")
		)
		(fp_line
			(start 0.120396 0.3048)
			(end 0.120396 0.2794)
			(stroke
				(width 0.1)
				(type default)
			)
			(layer "F.Fab")
		)
		(fp_line
			(start 0.67945 0.3048)
			(end 0.120396 0.3048)
			(stroke
				(width 0.1)
				(type default)
			)
			(layer "F.Fab")
		)
		(fp_line
			(start -0.12065 0.2794)
			(end -0.12065 0.3048)
			(stroke
				(width 0.1)
				(type default)
			)
			(layer "F.Fab")
		)
		(fp_line
			(start 0.120396 0.2794)
			(end -0.12065 0.2794)
			(stroke
				(width 0.1)
				(type default)
			)
			(layer "F.Fab")
		)
		(fp_line
			(start -0.12065 -0.2794)
			(end 0.12065 -0.2794)
			(stroke
				(width 0.1)
				(type default)
			)
			(layer "F.Fab")
		)
		(fp_line
			(start 0.12065 -0.2794)
			(end 0.12065 -0.3048)
			(stroke
				(width 0.1)
				(type default)
			)
			(layer "F.Fab")
		)
		(fp_line
			(start 0.12065 -0.3048)
			(end 0.67945 -0.3048)
			(stroke
				(width 0.1)
				(type default)
			)
			(layer "F.Fab")
		)
		(fp_line
			(start 0.67945 -0.3048)
			(end 0.67945 0.3048)
			(stroke
				(width 0.1)
				(type default)
			)
			(layer "F.Fab")
		)
		(fp_line
			(start -0.67945 -0.305054)
			(end -0.12065 -0.305054)
			(stroke
				(width 0.1)
				(type default)
			)
			(layer "F.Fab")
		)
		(fp_line
			(start -0.12065 -0.305054)
			(end -0.12065 -0.2794)
			(stroke
				(width 0.1)
				(type default)
			)
			(layer "F.Fab")
		)
		(pad "1" smd circle
			(at -0.40005 0 270)
			(size 0 0)
			(layers "F.Cu" "F.Mask" "F.Paste")
			(net "SW_PVDD11_S3_P1_BOOT1_RC")
		)
		(pad "2" smd circle
			(at 0.40005 0 270)
			(size 0 0)
			(layers "F.Cu" "F.Mask" "F.Paste")
			(net "SW_PVDD11_S3_P1_PH1")
		)
	)
	(footprint ""
		(layer "F.Cu")
		(at 79.629 -64.008 -90)
		(property "Reference" "U8002"
			(at 1.048766 -2.816606 90)
			(unlocked yes)
			(layer "F.SilkS")
			(effects
				(font
					(size 0.7874 0.5842)
					(thickness 0.1524)
				)
				(justify left)
			)
		)
		(property "Value" ""
			(at 0 0 270)
			(layer "F.Fab")
			(effects
				(font
					(size 1.27 1.27)
				)
			)
		)
		(duplicate_pad_numbers_are_jumpers no)
		(fp_line
			(start -1.759712 1.500124)
			(end -1.759712 -1.500124)
			(stroke
				(width 0.1524)
				(type default)
			)
			(layer "F.SilkS")
		)
		(fp_line
			(start 1.759712 1.500124)
			(end -1.759712 1.500124)
			(stroke
				(width 0.1524)
				(type default)
			)
			(layer "F.SilkS")
		)
		(fp_line
			(start -1.759712 -1.500124)
			(end 1.759712 -1.500124)
			(stroke
				(width 0.1524)
				(type default)
			)
			(layer "F.SilkS")
		)
		(fp_line
			(start 1.759712 -1.500124)
			(end 1.759712 1.500124)
			(stroke
				(width 0.1524)
				(type default)
			)
			(layer "F.SilkS")
		)
		(fp_line
			(start -0.700024 1.500124)
			(end -0.700024 -1.500124)
			(stroke
				(width 0.1)
				(type default)
			)
			(layer "F.Fab")
		)
		(fp_line
			(start 0.700024 1.500124)
			(end -0.700024 1.500124)
			(stroke
				(width 0.1)
				(type default)
			)
			(layer "F.Fab")
		)
		(fp_line
			(start -0.700024 -1.500124)
			(end 0.700024 -1.500124)
			(stroke
				(width 0.1)
				(type default)
			)
			(layer "F.Fab")
		)
		(fp_line
			(start 0.700024 -1.500124)
			(end 0.700024 1.500124)
			(stroke
				(width 0.1)
				(type default)
			)
			(layer "F.Fab")
		)
		(pad "1" smd rect
			(at -1.150112 -0.94996 180)
			(size 0.6604 0.9652)
			(layers "F.Cu" "F.Mask" "F.Paste")
			(net "GND")
		)
		(pad "2" smd rect
			(at -1.150112 0.94996 180)
			(size 0.6604 0.9652)
			(layers "F.Cu" "F.Mask" "F.Paste")
			(net "OCP_V3_2_P3V3_R1_PWRGD")
		)
		(pad "3" smd rect
			(at 1.150112 0 180)
			(size 0.6604 0.9652)
			(layers "F.Cu" "F.Mask" "F.Paste")
			(net "P3V3_OCP_V3_2_R")
		)
	)
	(footprint ""
		(layer "F.Cu")
		(at 275.574252 -119.91467)
		(property "Reference" "R6211"
			(at 0 0 0)
			(layer "F.SilkS")
			(hide yes)
			(effects
				(font
					(size 1.27 1.27)
				)
			)
		)
		(property "Value" ""
			(at 0 0 0)
			(layer "F.Fab")
			(effects
				(font
					(size 1.27 1.27)
				)
			)
		)
		(duplicate_pad_numbers_are_jumpers no)
		(fp_line
			(start -0.7874 -0.4064)
			(end 0.7874 -0.4064)
			(stroke
				(width 0.1524)
				(type default)
			)
			(layer "F.SilkS")
		)
		(fp_line
			(start -0.7874 0.4064)
			(end -0.7874 -0.4064)
			(stroke
				(width 0.1524)
				(type default)
			)
			(layer "F.SilkS")
		)
		(fp_line
			(start 0.7874 -0.4064)
			(end 0.7874 0.4064)
			(stroke
				(width 0.1524)
				(type default)
			)
			(layer "F.SilkS")
		)
		(fp_line
			(start 0.7874 0.4064)
			(end -0.7874 0.4064)
			(stroke
				(width 0.1524)
				(type default)
			)
			(layer "F.SilkS")
		)
		(fp_line
			(start -0.67945 -0.305054)
			(end -0.12065 -0.305054)
			(stroke
				(width 0.1)
				(type default)
			)
			(layer "F.Fab")
		)
		(fp_line
			(start -0.67945 0.3048)
			(end -0.67945 -0.305054)
			(stroke
				(width 0.1)
				(type default)
			)
			(layer "F.Fab")
		)
		(fp_line
			(start -0.12065 -0.305054)
			(end -0.12065 -0.2794)
			(stroke
				(width 0.1)
				(type default)
			)
			(layer "F.Fab")
		)
		(fp_line
			(start -0.12065 -0.2794)
			(end 0.12065 -0.2794)
			(stroke
				(width 0.1)
				(type default)
			)
			(layer "F.Fab")
		)
		(fp_line
			(start -0.12065 0.2794)
			(end -0.12065 0.3048)
			(stroke
				(width 0.1)
				(type default)
			)
			(layer "F.Fab")
		)
		(fp_line
			(start -0.12065 0.3048)
			(end -0.67945 0.3048)
			(stroke
				(width 0.1)
				(type default)
			)
			(layer "F.Fab")
		)
		(fp_line
			(start 0.120396 0.2794)
			(end -0.12065 0.2794)
			(stroke
				(width 0.1)
				(type default)
			)
			(layer "F.Fab")
		)
		(fp_line
			(start 0.120396 0.3048)
			(end 0.120396 0.2794)
			(stroke
				(width 0.1)
				(type default)
			)
			(layer "F.Fab")
		)
		(fp_line
			(start 0.12065 -0.3048)
			(end 0.67945 -0.3048)
			(stroke
				(width 0.1)
				(type default)
			)
			(layer "F.Fab")
		)
		(fp_line
			(start 0.12065 -0.2794)
			(end 0.12065 -0.3048)
			(stroke
				(width 0.1)
				(type default)
			)
			(layer "F.Fab")
		)
		(fp_line
			(start 0.67945 -0.3048)
			(end 0.67945 0.3048)
			(stroke
				(width 0.1)
				(type default)
			)
			(layer "F.Fab")
		)
		(fp_line
			(start 0.67945 0.3048)
			(end 0.120396 0.3048)
			(stroke
				(width 0.1)
				(type default)
			)
			(layer "F.Fab")
		)
		(pad "1" smd circle
			(at -0.40005 0)
			(size 0 0)
			(layers "F.Cu" "F.Mask" "F.Paste")
			(net "P3V3_AUX")
		)
		(pad "2" smd circle
			(at 0.40005 0)
			(size 0 0)
			(layers "F.Cu" "F.Mask" "F.Paste")
			(net "SMB_USB_CPU0_HUB1_SCL")
		)
	)
)
